(kicad_pcb
	(version 20260206)
	(generator "pcbnew")
	(generator_version "10.0")
	(general
		(thickness 1.6)
		(legacy_teardrops no)
	)
	(paper "A4")
	(title_block
		(title "12092022_DA0F0TMDCD0_F0T_Management_Board_D_brd_V3_OCP.brd")
		(comment 1 "Grand Teton / footprints 1016-1022 of 1440")
	)
	(layers
		(0 "F.Cu" signal "TOP")
		(4 "In1.Cu" signal "GND")
		(6 "In2.Cu" signal "IN1")
		(8 "In3.Cu" signal "GND1")
		(10 "In4.Cu" signal "IN2")
		(12 "In5.Cu" signal "VCC")
		(14 "In6.Cu" signal "VCC1")
		(16 "In7.Cu" signal "IN3")
		(18 "In8.Cu" signal "GND2")
		(20 "In9.Cu" signal "IN4")
		(22 "In10.Cu" signal "GND3")
		(2 "B.Cu" signal "BOTTOM")
		(9 "F.Adhes" user "F.Adhesive")
		(11 "B.Adhes" user "B.Adhesive")
		(13 "F.Paste" user "Package Geometry/Pastemask Top")
		(15 "B.Paste" user "Package Geometry/Pastemask Bottom")
		(5 "F.SilkS" user "Ref Des/Silkscreen Top")
		(7 "B.SilkS" user "Ref Des/Silkscreen Bottom")
		(1 "F.Mask" user "Board Geometry/Soldermask Top")
		(3 "B.Mask" user "Board Geometry/Soldermask Bottom")
		(17 "Dwgs.User" user "User.Drawings")
		(19 "Cmts.User" user "User.Comments")
		(21 "Eco1.User" user "User.Eco1")
		(23 "Eco2.User" user "User.Eco2")
		(25 "Edge.Cuts" user "Board Geometry/Outline")
		(27 "Margin" user)
		(31 "F.CrtYd" user "Package Geometry/Place Bound Top")
		(29 "B.CrtYd" user "Package Geometry/Place Bound Bottom")
		(35 "F.Fab" user "Ref Des/Assembly Top")
		(33 "B.Fab" user "Ref Des/Assembly Bottom")
	)
	(footprint ""
		(layer "B.Cu")
		(at 20.80133 -77.50683 90)
		(property "Reference" "OSC2"
			(at -2.07518 2.46507 0)
			(unlocked yes)
			(layer "B.SilkS")
			(effects
				(font
					(size 0.635 0.4064)
					(thickness 0.1524)
				)
				(justify left mirror)
			)
		)
		(property "Value" ""
			(at 0 0 90)
			(layer "B.Fab")
			(effects
				(font
					(size 1.27 1.27)
				)
				(justify mirror)
			)
		)
		(duplicate_pad_numbers_are_jumpers no)
		(fp_line
			(start 1.397 -1.761236)
			(end 1.397 1.761236)
			(stroke
				(width 0.1524)
				(type default)
			)
			(layer "B.SilkS")
		)
		(fp_line
			(start -1.397 -1.761236)
			(end 1.397 -1.761236)
			(stroke
				(width 0.1524)
				(type default)
			)
			(layer "B.SilkS")
		)
		(fp_line
			(start 1.397 1.761236)
			(end -1.397 1.761236)
			(stroke
				(width 0.1524)
				(type default)
			)
			(layer "B.SilkS")
		)
		(fp_line
			(start -1.397 1.761236)
			(end -1.397 -1.761236)
			(stroke
				(width 0.1524)
				(type default)
			)
			(layer "B.SilkS")
		)
		(fp_poly
			(pts
				(xy 1.965706 -0.825246) (xy 3.043428 -0.46609) (xy 2.324862 0.252476)
			)
			(stroke
				(width 0)
				(type default)
			)
			(fill yes)
			(layer "B.SilkS")
		)
		(fp_line
			(start 1.299972 -1.649984)
			(end -1.299972 -1.649984)
			(stroke
				(width 0.1)
				(type default)
			)
			(layer "B.Fab")
		)
		(fp_line
			(start -1.299972 -1.649984)
			(end -1.299972 1.649984)
			(stroke
				(width 0.1)
				(type default)
			)
			(layer "B.Fab")
		)
		(fp_line
			(start 1.299972 1.649984)
			(end 1.299972 -1.649984)
			(stroke
				(width 0.1)
				(type default)
			)
			(layer "B.Fab")
		)
		(fp_line
			(start -1.299972 1.649984)
			(end 1.299972 1.649984)
			(stroke
				(width 0.1)
				(type default)
			)
			(layer "B.Fab")
		)
		(fp_poly
			(pts
				(xy 1.694688 -1.050036) (xy 2.710688 -1.558036) (xy 2.710688 -0.542036)
			)
			(stroke
				(width 0)
				(type default)
			)
			(fill yes)
			(layer "B.Fab")
		)
		(pad "1" smd rect
			(at 0.824992 -1.050036 270)
			(size 0.8636 1.1684)
			(layers "B.Cu" "B.Mask" "B.Paste")
			(net "PU_25M_FPGA_CLK_EN")
		)
		(pad "2" smd rect
			(at 0.824992 1.050036 270)
			(size 0.8636 1.1684)
			(layers "B.Cu" "B.Mask" "B.Paste")
			(net "GND")
		)
		(pad "3" smd rect
			(at -0.824992 1.050036 270)
			(size 0.8636 1.1684)
			(layers "B.Cu" "B.Mask" "B.Paste")
			(net "CLK_25M_OSC_FPGA_R")
		)
		(pad "4" smd rect
			(at -0.824992 -1.050036 270)
			(size 0.8636 1.1684)
			(layers "B.Cu" "B.Mask" "B.Paste")
			(net "P3V3_AUX")
		)
	)
	(footprint ""
		(layer "B.Cu")
		(at 42.183558 -84.33816 90)
		(property "Reference" "U11"
			(at 0.26924 2.303272 270)
			(unlocked yes)
			(layer "B.SilkS")
			(effects
				(font
					(size 0.7874 0.5842)
					(thickness 0.1524)
				)
				(justify mirror)
			)
		)
		(property "Value" ""
			(at 0 0 90)
			(layer "B.Fab")
			(effects
				(font
					(size 1.27 1.27)
				)
				(justify mirror)
			)
		)
		(duplicate_pad_numbers_are_jumpers no)
		(fp_line
			(start 1.905 -1.651)
			(end -1.905 -1.651)
			(stroke
				(width 0.1524)
				(type default)
			)
			(layer "B.SilkS")
		)
		(fp_line
			(start -1.905 -1.651)
			(end -1.905 1.651)
			(stroke
				(width 0.1524)
				(type default)
			)
			(layer "B.SilkS")
		)
		(fp_line
			(start 1.905 1.651)
			(end 1.905 -1.651)
			(stroke
				(width 0.1524)
				(type default)
			)
			(layer "B.SilkS")
		)
		(fp_line
			(start -1.905 1.651)
			(end 1.905 1.651)
			(stroke
				(width 0.1524)
				(type default)
			)
			(layer "B.SilkS")
		)
		(fp_line
			(start 0.649986 -1.524)
			(end -0.6985 -1.524)
			(stroke
				(width 0.1)
				(type default)
			)
			(layer "B.Fab")
		)
		(fp_line
			(start -0.6985 -1.524)
			(end -0.6985 -0.219964)
			(stroke
				(width 0.1)
				(type default)
			)
			(layer "B.Fab")
		)
		(fp_line
			(start 1.249934 -1.169924)
			(end 0.649986 -1.169924)
			(stroke
				(width 0.1)
				(type default)
			)
			(layer "B.Fab")
		)
		(fp_line
			(start 0.649986 -1.169924)
			(end 0.649986 -1.524)
			(stroke
				(width 0.1)
				(type default)
			)
			(layer "B.Fab")
		)
		(fp_line
			(start 1.249934 -0.729996)
			(end 1.249934 -1.169924)
			(stroke
				(width 0.1)
				(type default)
			)
			(layer "B.Fab")
		)
		(fp_line
			(start 0.6985 -0.729996)
			(end 1.249934 -0.729996)
			(stroke
				(width 0.1)
				(type default)
			)
			(layer "B.Fab")
		)
		(fp_line
			(start -0.6985 -0.219964)
			(end -1.249934 -0.219964)
			(stroke
				(width 0.1)
				(type default)
			)
			(layer "B.Fab")
		)
		(fp_line
			(start -1.249934 -0.219964)
			(end -1.249934 0.219964)
			(stroke
				(width 0.1)
				(type default)
			)
			(layer "B.Fab")
		)
		(fp_line
			(start -0.6985 0.219964)
			(end -0.6985 1.524)
			(stroke
				(width 0.1)
				(type default)
			)
			(layer "B.Fab")
		)
		(fp_line
			(start -1.249934 0.219964)
			(end -0.6985 0.219964)
			(stroke
				(width 0.1)
				(type default)
			)
			(layer "B.Fab")
		)
		(fp_line
			(start 1.249934 0.729996)
			(end 0.6985 0.729996)
			(stroke
				(width 0.1)
				(type default)
			)
			(layer "B.Fab")
		)
		(fp_line
			(start 0.6985 0.729996)
			(end 0.6985 -0.729996)
			(stroke
				(width 0.1)
				(type default)
			)
			(layer "B.Fab")
		)
		(fp_line
			(start 1.249934 1.169924)
			(end 1.249934 0.729996)
			(stroke
				(width 0.1)
				(type default)
			)
			(layer "B.Fab")
		)
		(fp_line
			(start 0.649986 1.169924)
			(end 1.249934 1.169924)
			(stroke
				(width 0.1)
				(type default)
			)
			(layer "B.Fab")
		)
		(fp_line
			(start 0.649986 1.524)
			(end 0.649986 1.169924)
			(stroke
				(width 0.1)
				(type default)
			)
			(layer "B.Fab")
		)
		(fp_line
			(start -0.6985 1.524)
			(end 0.649986 1.524)
			(stroke
				(width 0.1)
				(type default)
			)
			(layer "B.Fab")
		)
		(pad "1" smd rect
			(at 1.1176 -1.016)
			(size 1.016 1.27)
			(layers "B.Cu" "B.Mask" "B.Paste")
			(net "FM_BMC_ONCTL_R_N")
		)
		(pad "2" smd rect
			(at 1.1176 1.016)
			(size 1.016 1.27)
			(layers "B.Cu" "B.Mask" "B.Paste")
			(net "UART_BMC_5_TXD_R")
		)
		(pad "3" smd rect
			(at -1.1176 0)
			(size 1.016 1.27)
			(layers "B.Cu" "B.Mask" "B.Paste")
			(net "FM_BMC_DISABLE")
		)
	)
	(footprint ""
		(layer "B.Cu")
		(at 74.095356 -99.906328)
		(property "Reference" "R714"
			(at 0 0 0)
			(layer "B.SilkS")
			(hide yes)
			(effects
				(font
					(size 1.27 1.27)
				)
				(justify mirror)
			)
		)
		(property "Value" ""
			(at 0 0 0)
			(layer "B.Fab")
			(effects
				(font
					(size 1.27 1.27)
				)
				(justify mirror)
			)
		)
		(duplicate_pad_numbers_are_jumpers no)
		(fp_line
			(start -0.7874 -0.4064)
			(end -0.7874 0.4064)
			(stroke
				(width 0.1524)
				(type default)
			)
			(layer "B.SilkS")
		)
		(fp_line
			(start -0.7874 0.4064)
			(end 0.7874 0.4064)
			(stroke
				(width 0.1524)
				(type default)
			)
			(layer "B.SilkS")
		)
		(fp_line
			(start 0.7874 -0.4064)
			(end -0.7874 -0.4064)
			(stroke
				(width 0.1524)
				(type default)
			)
			(layer "B.SilkS")
		)
		(fp_line
			(start 0.7874 0.4064)
			(end 0.7874 -0.4064)
			(stroke
				(width 0.1524)
				(type default)
			)
			(layer "B.SilkS")
		)
		(fp_line
			(start -0.67945 -0.3048)
			(end -0.67945 0.3048)
			(stroke
				(width 0.1)
				(type default)
			)
			(layer "B.Fab")
		)
		(fp_line
			(start -0.67945 0.3048)
			(end -0.120396 0.3048)
			(stroke
				(width 0.1)
				(type default)
			)
			(layer "B.Fab")
		)
		(fp_line
			(start -0.12065 -0.3048)
			(end -0.67945 -0.3048)
			(stroke
				(width 0.1)
				(type default)
			)
			(layer "B.Fab")
		)
		(fp_line
			(start -0.12065 -0.2794)
			(end -0.12065 -0.3048)
			(stroke
				(width 0.1)
				(type default)
			)
			(layer "B.Fab")
		)
		(fp_line
			(start -0.120396 0.2794)
			(end 0.12065 0.2794)
			(stroke
				(width 0.1)
				(type default)
			)
			(layer "B.Fab")
		)
		(fp_line
			(start -0.120396 0.3048)
			(end -0.120396 0.2794)
			(stroke
				(width 0.1)
				(type default)
			)
			(layer "B.Fab")
		)
		(fp_line
			(start 0.12065 -0.305054)
			(end 0.12065 -0.2794)
			(stroke
				(width 0.1)
				(type default)
			)
			(layer "B.Fab")
		)
		(fp_line
			(start 0.12065 -0.2794)
			(end -0.12065 -0.2794)
			(stroke
				(width 0.1)
				(type default)
			)
			(layer "B.Fab")
		)
		(fp_line
			(start 0.12065 0.2794)
			(end 0.12065 0.3048)
			(stroke
				(width 0.1)
				(type default)
			)
			(layer "B.Fab")
		)
		(fp_line
			(start 0.12065 0.3048)
			(end 0.67945 0.3048)
			(stroke
				(width 0.1)
				(type default)
			)
			(layer "B.Fab")
		)
		(fp_line
			(start 0.67945 -0.305054)
			(end 0.12065 -0.305054)
			(stroke
				(width 0.1)
				(type default)
			)
			(layer "B.Fab")
		)
		(fp_line
			(start 0.67945 0.3048)
			(end 0.67945 -0.305054)
			(stroke
				(width 0.1)
				(type default)
			)
			(layer "B.Fab")
		)
		(pad "1" smd circle
			(at 0.40005 0 180)
			(size 0 0)
			(layers "B.Cu" "B.Mask" "B.Paste")
			(net "LPC_ESPI_SEL")
		)
		(pad "2" smd circle
			(at -0.40005 0 180)
			(size 0 0)
			(layers "B.Cu" "B.Mask" "B.Paste")
			(net "LPC_ESPI_SEL_R1")
		)
	)
	(footprint ""
		(layer "B.Cu")
		(at 34.8996 -82.2452)
		(property "Reference" ""
			(at 0 0 0)
			(layer "B.SilkS")
			(hide yes)
			(effects
				(font
					(size 1.27 1.27)
				)
				(justify mirror)
			)
		)
		(property "Value" ""
			(at 0 0 0)
			(layer "B.Fab")
			(effects
				(font
					(size 1.27 1.27)
				)
				(justify mirror)
			)
		)
		(duplicate_pad_numbers_are_jumpers no)
		(pad "1" smd circle
			(at 0 0 180)
			(size 0.9906 0.9906)
			(layers "B.Cu" "B.Mask" "B.Paste")
			(net "Net_595")
		)
		(zone
			(layer "B.Cu")
			(hatch none 0.5)
			(connect_pads
				(clearance 0)
			)
			(min_thickness 0.25)
			(keepout
				(tracks not_allowed)
				(vias allowed)
				(pads allowed)
				(copperpour not_allowed)
				(footprints allowed)
			)
			(placement
				(enabled no)
				(sheetname "")
			)
			(fill
				(thermal_gap 0.5)
				(thermal_bridge_width 0.5)
				(island_removal_mode 0)
			)
			(polygon
				(pts
					(arc
						(start 36.5252 -82.2452)
						(mid 33.274 -82.2452)
						(end 36.5252 -82.2452)
					)
				)
			)
		)
	)
	(footprint ""
		(layer "B.Cu")
		(at 41.9608 -43.9928 180)
		(property "Reference" "R444"
			(at 0 0 0)
			(layer "B.SilkS")
			(hide yes)
			(effects
				(font
					(size 1.27 1.27)
				)
				(justify mirror)
			)
		)
		(property "Value" ""
			(at 0 0 0)
			(layer "B.Fab")
			(effects
				(font
					(size 1.27 1.27)
				)
				(justify mirror)
			)
		)
		(duplicate_pad_numbers_are_jumpers no)
		(fp_line
			(start 0.7874 0.4064)
			(end 0.7874 -0.4064)
			(stroke
				(width 0.1524)
				(type default)
			)
			(layer "B.SilkS")
		)
		(fp_line
			(start 0.7874 -0.4064)
			(end -0.7874 -0.4064)
			(stroke
				(width 0.1524)
				(type default)
			)
			(layer "B.SilkS")
		)
		(fp_line
			(start -0.7874 0.4064)
			(end 0.7874 0.4064)
			(stroke
				(width 0.1524)
				(type default)
			)
			(layer "B.SilkS")
		)
		(fp_line
			(start -0.7874 -0.4064)
			(end -0.7874 0.4064)
			(stroke
				(width 0.1524)
				(type default)
			)
			(layer "B.SilkS")
		)
		(fp_line
			(start 0.67945 0.3048)
			(end 0.67945 -0.305054)
			(stroke
				(width 0.1)
				(type default)
			)
			(layer "B.Fab")
		)
		(fp_line
			(start 0.67945 -0.305054)
			(end 0.12065 -0.305054)
			(stroke
				(width 0.1)
				(type default)
			)
			(layer "B.Fab")
		)
		(fp_line
			(start 0.12065 0.3048)
			(end 0.67945 0.3048)
			(stroke
				(width 0.1)
				(type default)
			)
			(layer "B.Fab")
		)
		(fp_line
			(start 0.12065 0.2794)
			(end 0.12065 0.3048)
			(stroke
				(width 0.1)
				(type default)
			)
			(layer "B.Fab")
		)
		(fp_line
			(start 0.12065 -0.2794)
			(end -0.12065 -0.2794)
			(stroke
				(width 0.1)
				(type default)
			)
			(layer "B.Fab")
		)
		(fp_line
			(start 0.12065 -0.305054)
			(end 0.12065 -0.2794)
			(stroke
				(width 0.1)
				(type default)
			)
			(layer "B.Fab")
		)
		(fp_line
			(start -0.120396 0.3048)
			(end -0.120396 0.2794)
			(stroke
				(width 0.1)
				(type default)
			)
			(layer "B.Fab")
		)
		(fp_line
			(start -0.120396 0.2794)
			(end 0.12065 0.2794)
			(stroke
				(width 0.1)
				(type default)
			)
			(layer "B.Fab")
		)
		(fp_line
			(start -0.12065 -0.2794)
			(end -0.12065 -0.3048)
			(stroke
				(width 0.1)
				(type default)
			)
			(layer "B.Fab")
		)
		(fp_line
			(start -0.12065 -0.3048)
			(end -0.67945 -0.3048)
			(stroke
				(width 0.1)
				(type default)
			)
			(layer "B.Fab")
		)
		(fp_line
			(start -0.67945 0.3048)
			(end -0.120396 0.3048)
			(stroke
				(width 0.1)
				(type default)
			)
			(layer "B.Fab")
		)
		(fp_line
			(start -0.67945 -0.3048)
			(end -0.67945 0.3048)
			(stroke
				(width 0.1)
				(type default)
			)
			(layer "B.Fab")
		)
		(pad "1" smd circle
			(at 0.40005 0)
			(size 0 0)
			(layers "B.Cu" "B.Mask" "B.Paste")
			(net "FM_ESPI_PLD_EN")
		)
		(pad "2" smd circle
			(at -0.40005 0)
			(size 0 0)
			(layers "B.Cu" "B.Mask" "B.Paste")
			(net "FM_ESPI_PLD_R1_EN")
		)
	)
	(footprint ""
		(layer "B.Cu")
		(at 26.035 -101.981 -90)
		(property "Reference" "R627"
			(at 0 0 90)
			(layer "B.SilkS")
			(hide yes)
			(effects
				(font
					(size 1.27 1.27)
				)
				(justify mirror)
			)
		)
		(property "Value" ""
			(at 0 0 90)
			(layer "B.Fab")
			(effects
				(font
					(size 1.27 1.27)
				)
				(justify mirror)
			)
		)
		(duplicate_pad_numbers_are_jumpers no)
		(fp_line
			(start -0.7874 0.4064)
			(end 0.7874 0.4064)
			(stroke
				(width 0.1524)
				(type default)
			)
			(layer "B.SilkS")
		)
		(fp_line
			(start 0.7874 0.4064)
			(end 0.7874 -0.4064)
			(stroke
				(width 0.1524)
				(type default)
			)
			(layer "B.SilkS")
		)
		(fp_line
			(start -0.7874 -0.4064)
			(end -0.7874 0.4064)
			(stroke
				(width 0.1524)
				(type default)
			)
			(layer "B.SilkS")
		)
		(fp_line
			(start 0.7874 -0.4064)
			(end -0.7874 -0.4064)
			(stroke
				(width 0.1524)
				(type default)
			)
			(layer "B.SilkS")
		)
		(fp_line
			(start -0.67945 0.3048)
			(end -0.120396 0.3048)
			(stroke
				(width 0.1)
				(type default)
			)
			(layer "B.Fab")
		)
		(fp_line
			(start -0.120396 0.3048)
			(end -0.120396 0.2794)
			(stroke
				(width 0.1)
				(type default)
			)
			(layer "B.Fab")
		)
		(fp_line
			(start 0.12065 0.3048)
			(end 0.67945 0.3048)
			(stroke
				(width 0.1)
				(type default)
			)
			(layer "B.Fab")
		)
		(fp_line
			(start 0.67945 0.3048)
			(end 0.67945 -0.305054)
			(stroke
				(width 0.1)
				(type default)
			)
			(layer "B.Fab")
		)
		(fp_line
			(start -0.120396 0.2794)
			(end 0.12065 0.2794)
			(stroke
				(width 0.1)
				(type default)
			)
			(layer "B.Fab")
		)
		(fp_line
			(start 0.12065 0.2794)
			(end 0.12065 0.3048)
			(stroke
				(width 0.1)
				(type default)
			)
			(layer "B.Fab")
		)
		(fp_line
			(start -0.12065 -0.2794)
			(end -0.12065 -0.3048)
			(stroke
				(width 0.1)
				(type default)
			)
			(layer "B.Fab")
		)
		(fp_line
			(start 0.12065 -0.2794)
			(end -0.12065 -0.2794)
			(stroke
				(width 0.1)
				(type default)
			)
			(layer "B.Fab")
		)
		(fp_line
			(start -0.67945 -0.3048)
			(end -0.67945 0.3048)
			(stroke
				(width 0.1)
				(type default)
			)
			(layer "B.Fab")
		)
		(fp_line
			(start -0.12065 -0.3048)
			(end -0.67945 -0.3048)
			(stroke
				(width 0.1)
				(type default)
			)
			(layer "B.Fab")
		)
		(fp_line
			(start 0.12065 -0.305054)
			(end 0.12065 -0.2794)
			(stroke
				(width 0.1)
				(type default)
			)
			(layer "B.Fab")
		)
		(fp_line
			(start 0.67945 -0.305054)
			(end 0.12065 -0.305054)
			(stroke
				(width 0.1)
				(type default)
			)
			(layer "B.Fab")
		)
		(pad "1" smd circle
			(at 0.40005 0 90)
			(size 0 0)
			(layers "B.Cu" "B.Mask" "B.Paste")
			(net "P3V3_AUX")
		)
		(pad "2" smd circle
			(at -0.40005 0 90)
			(size 0 0)
			(layers "B.Cu" "B.Mask" "B.Paste")
			(net "PWRGD_DSW_PWROK")
		)
	)
	(footprint ""
		(layer "B.Cu")
		(at 50.927 -76.3016)
		(property "Reference" "R55"
			(at 0 0 0)
			(layer "B.SilkS")
			(hide yes)
			(effects
				(font
					(size 1.27 1.27)
				)
				(justify mirror)
			)
		)
		(property "Value" ""
			(at 0 0 0)
			(layer "B.Fab")
			(effects
				(font
					(size 1.27 1.27)
				)
				(justify mirror)
			)
		)
		(duplicate_pad_numbers_are_jumpers no)
		(fp_line
			(start -0.7874 -0.4064)
			(end -0.7874 0.4064)
			(stroke
				(width 0.1524)
				(type default)
			)
			(layer "B.SilkS")
		)
		(fp_line
			(start -0.7874 0.4064)
			(end 0.7874 0.4064)
			(stroke
				(width 0.1524)
				(type default)
			)
			(layer "B.SilkS")
		)
		(fp_line
			(start 0.7874 -0.4064)
			(end -0.7874 -0.4064)
			(stroke
				(width 0.1524)
				(type default)
			)
			(layer "B.SilkS")
		)
		(fp_line
			(start 0.7874 0.4064)
			(end 0.7874 -0.4064)
			(stroke
				(width 0.1524)
				(type default)
			)
			(layer "B.SilkS")
		)
		(fp_line
			(start -0.67945 -0.3048)
			(end -0.67945 0.3048)
			(stroke
				(width 0.1)
				(type default)
			)
			(layer "B.Fab")
		)
		(fp_line
			(start -0.67945 0.3048)
			(end -0.120396 0.3048)
			(stroke
				(width 0.1)
				(type default)
			)
			(layer "B.Fab")
		)
		(fp_line
			(start -0.12065 -0.3048)
			(end -0.67945 -0.3048)
			(stroke
				(width 0.1)
				(type default)
			)
			(layer "B.Fab")
		)
		(fp_line
			(start -0.12065 -0.2794)
			(end -0.12065 -0.3048)
			(stroke
				(width 0.1)
				(type default)
			)
			(layer "B.Fab")
		)
		(fp_line
			(start -0.120396 0.2794)
			(end 0.12065 0.2794)
			(stroke
				(width 0.1)
				(type default)
			)
			(layer "B.Fab")
		)
		(fp_line
			(start -0.120396 0.3048)
			(end -0.120396 0.2794)
			(stroke
				(width 0.1)
				(type default)
			)
			(layer "B.Fab")
		)
		(fp_line
			(start 0.12065 -0.305054)
			(end 0.12065 -0.2794)
			(stroke
				(width 0.1)
				(type default)
			)
			(layer "B.Fab")
		)
		(fp_line
			(start 0.12065 -0.2794)
			(end -0.12065 -0.2794)
			(stroke
				(width 0.1)
				(type default)
			)
			(layer "B.Fab")
		)
		(fp_line
			(start 0.12065 0.2794)
			(end 0.12065 0.3048)
			(stroke
				(width 0.1)
				(type default)
			)
			(layer "B.Fab")
		)
		(fp_line
			(start 0.12065 0.3048)
			(end 0.67945 0.3048)
			(stroke
				(width 0.1)
				(type default)
			)
			(layer "B.Fab")
		)
		(fp_line
			(start 0.67945 -0.305054)
			(end 0.12065 -0.305054)
			(stroke
				(width 0.1)
				(type default)
			)
			(layer "B.Fab")
		)
		(fp_line
			(start 0.67945 0.3048)
			(end 0.67945 -0.305054)
			(stroke
				(width 0.1)
				(type default)
			)
			(layer "B.Fab")
		)
		(pad "1" smd circle
			(at 0.40005 0 180)
			(size 0 0)
			(layers "B.Cu" "B.Mask" "B.Paste")
			(net "P3V3_AUX")
		)
		(pad "2" smd circle
			(at -0.40005 0 180)
			(size 0 0)
			(layers "B.Cu" "B.Mask" "B.Paste")
			(net "FM_BMC_READY_R_PLD_N")
		)
	)
)
